(kicad_pcb
	(version 20260206)
	(generator "pcbnew")
	(generator_version "10.0")
	(general
		(thickness 1.6)
		(legacy_teardrops no)
	)
	(paper "A4")
	(title_block
		(title "03242023_DA0F0TMBIJ0_F0T_Motherboard_J_brd_V01_OCP.brd")
		(comment 1 "Grand Teton / footprint 1682 of 6105 (U1), pads 3461-3567 of 4677")
	)
	(layers
		(0 "F.Cu" signal "TOP")
		(4 "In1.Cu" signal "GND")
		(6 "In2.Cu" signal "IN1")
		(8 "In3.Cu" signal "GND1")
		(10 "In4.Cu" signal "IN2")
		(12 "In5.Cu" signal "GND2")
		(14 "In6.Cu" signal "IN3")
		(16 "In7.Cu" signal "GND3")
		(18 "In8.Cu" signal "VCC")
		(20 "In9.Cu" signal "VCC1")
		(22 "In10.Cu" signal "GND4")
		(24 "In11.Cu" signal "IN4")
		(26 "In12.Cu" signal "GND5")
		(28 "In13.Cu" signal "IN5")
		(30 "In14.Cu" signal "GND6")
		(32 "In15.Cu" signal "IN6")
		(34 "In16.Cu" signal "GND7")
		(2 "B.Cu" signal "BOTTOM")
		(9 "F.Adhes" user "F.Adhesive")
		(11 "B.Adhes" user "B.Adhesive")
		(13 "F.Paste" user "Package Geometry/Pastemask Top")
		(15 "B.Paste" user "Package Geometry/Pastemask Bottom")
		(5 "F.SilkS" user "Ref Des/Silkscreen Top")
		(7 "B.SilkS" user "Ref Des/Silkscreen Bottom")
		(1 "F.Mask" user "Board Geometry/Soldermask Top")
		(3 "B.Mask" user "Board Geometry/Soldermask Bottom")
		(17 "Dwgs.User" user "User.Drawings")
		(19 "Cmts.User" user "User.Comments")
		(21 "Eco1.User" user "User.Eco1")
		(23 "Eco2.User" user "User.Eco2")
		(25 "Edge.Cuts" user "Board Geometry/Outline")
		(27 "Margin" user)
		(31 "F.CrtYd" user "Package Geometry/Place Bound Top")
		(29 "B.CrtYd" user "Package Geometry/Place Bound Bottom")
		(35 "F.Fab" user "Ref Des/Assembly Top")
		(33 "B.Fab" user "Ref Des/Assembly Bottom")
	)
	(footprint ""
		(layer "F.Cu")
		(at 111.93018 -251.76988 90)
		(property "Reference" "U1"
			(at -74.913236 41.548812 0)
			(unlocked yes)
			(layer "F.SilkS")
			(effects
				(font
					(size 1.6002 1.1938)
					(thickness 0.1524)
				)
				(justify left)
			)
		)
		(property "Value" ""
			(at 0 0 90)
			(layer "F.Fab")
			(effects
				(font
					(size 1.27 1.27)
				)
			)
		)
		(duplicate_pad_numbers_are_jumpers no)
		(pad "EC78" smd circle
			(at 26.844498 20.965668 270)
			(size 0.4318 0.4318)
			(layers "F.Cu" "F.Mask" "F.Paste")
			(net "PVCCFA_EHV_FIVRA_CPU1")
		)
		(pad "EC80" smd circle
			(at 28.472384 20.965668 270)
			(size 0.4318 0.4318)
			(layers "F.Cu" "F.Mask" "F.Paste")
			(net "GND")
		)
		(pad "EC82" smd circle
			(at 30.100016 20.965668 270)
			(size 0.4318 0.4318)
			(layers "F.Cu" "F.Mask" "F.Paste")
			(net "GND")
		)
		(pad "EC84" smd circle
			(at 31.727902 20.965668 270)
			(size 0.4318 0.4318)
			(layers "F.Cu" "F.Mask" "F.Paste")
			(net "GND")
		)
		(pad "EC86" smd circle
			(at 33.355534 20.965668 270)
			(size 0.4318 0.4318)
			(layers "F.Cu" "F.Mask" "F.Paste")
			(net "P5E_CPU1_PE3_TX_DP<1>")
		)
		(pad "EC88" smd circle
			(at 34.98342 20.965668 270)
			(size 0.4318 0.4318)
			(layers "F.Cu" "F.Mask" "F.Paste")
			(net "GND")
		)
		(pad "EC90" smd circle
			(at 36.611306 20.965668 270)
			(size 0.4318 0.4318)
			(layers "F.Cu" "F.Mask" "F.Paste")
			(net "P5E_CPU1_PE3_RX_DN<2>")
		)
		(pad "ED2" smd oval
			(at -36.611306 21.325332 180)
			(size 0.381 0.4826)
			(drill
				(offset 0 -0.0508)
			)
			(layers "F.Cu" "F.Mask" "F.Paste")
			(net "UPI_CPU0_CPU1_P0P1_DN<2>")
		)
		(pad "ED4" smd circle
			(at -34.98342 21.325332 270)
			(size 0.4318 0.4318)
			(layers "F.Cu" "F.Mask" "F.Paste")
			(net "GND")
		)
		(pad "ED6" smd circle
			(at -33.355534 21.325332 270)
			(size 0.4318 0.4318)
			(layers "F.Cu" "F.Mask" "F.Paste")
			(net "UPI_CPU1_CPU0_P1P0_DP<1>")
		)
		(pad "ED8" smd circle
			(at -31.727902 21.325332 270)
			(size 0.4318 0.4318)
			(layers "F.Cu" "F.Mask" "F.Paste")
			(net "GND")
		)
		(pad "ED10" smd circle
			(at -30.100016 21.325332 270)
			(size 0.4318 0.4318)
			(layers "F.Cu" "F.Mask" "F.Paste")
			(net "P5E_CPU1_PE2_RX_DN<13>")
		)
		(pad "ED12" smd circle
			(at -28.472384 21.325332 270)
			(size 0.4318 0.4318)
			(layers "F.Cu" "F.Mask" "F.Paste")
			(net "GND")
		)
		(pad "ED14" smd circle
			(at -26.844498 21.325332 270)
			(size 0.4318 0.4318)
			(layers "F.Cu" "F.Mask" "F.Paste")
			(net "P5E_CPU1_PE2_TX_DP<14>")
		)
		(pad "ED16" smd circle
			(at -25.216612 21.325332 270)
			(size 0.4318 0.4318)
			(layers "F.Cu" "F.Mask" "F.Paste")
			(net "GND")
		)
		(pad "ED18" smd circle
			(at -23.58898 21.325332 270)
			(size 0.4318 0.4318)
			(layers "F.Cu" "F.Mask" "F.Paste")
			(net "GND")
		)
		(pad "ED20" smd circle
			(at -21.961094 21.325332 270)
			(size 0.4318 0.4318)
			(layers "F.Cu" "F.Mask" "F.Paste")
			(net "M_F_CPU1_SB_DQ<12>")
		)
		(pad "ED22" smd circle
			(at -20.333462 21.325332 270)
			(size 0.4318 0.4318)
			(layers "F.Cu" "F.Mask" "F.Paste")
			(net "M_F_CPU1_SB_DQ<9>")
		)
		(pad "ED24" smd circle
			(at -18.705576 21.325332 270)
			(size 0.4318 0.4318)
			(layers "F.Cu" "F.Mask" "F.Paste")
			(net "GND")
		)
		(pad "ED26" smd circle
			(at -17.07769 21.325332 270)
			(size 0.4318 0.4318)
			(layers "F.Cu" "F.Mask" "F.Paste")
			(net "M_E_CPU1_SB_DQ<4>")
		)
		(pad "ED28" smd circle
			(at -15.450058 21.325332 270)
			(size 0.4318 0.4318)
			(layers "F.Cu" "F.Mask" "F.Paste")
			(net "M_E_CPU1_SB_DQ<1>")
		)
		(pad "ED30" smd circle
			(at -13.822426 21.325332 270)
			(size 0.4318 0.4318)
			(layers "F.Cu" "F.Mask" "F.Paste")
			(net "GND")
		)
		(pad "ED32" smd circle
			(at -12.19454 21.325332 270)
			(size 0.4318 0.4318)
			(layers "F.Cu" "F.Mask" "F.Paste")
			(net "M_F_CPU1_SB_CB<0>")
		)
		(pad "ED34" smd circle
			(at -10.566654 21.325332 270)
			(size 0.4318 0.4318)
			(layers "F.Cu" "F.Mask" "F.Paste")
			(net "M_F_CPU1_SB_CB<5>")
		)
		(pad "ED36" smd circle
			(at -8.939022 21.325332 270)
			(size 0.4318 0.4318)
			(layers "F.Cu" "F.Mask" "F.Paste")
			(net "GND")
		)
		(pad "ED38" smd circle
			(at -7.311136 21.325332 270)
			(size 0.4318 0.4318)
			(layers "F.Cu" "F.Mask" "F.Paste")
			(net "M_F_CPU1_SB_CS_N<2>")
		)
		(pad "ED40" smd circle
			(at -5.68325 21.325332 270)
			(size 0.4318 0.4318)
			(layers "F.Cu" "F.Mask" "F.Paste")
			(net "M_F_CPU1_SB_CA<4>")
		)
		(pad "ED42" smd circle
			(at -4.055618 21.325332 270)
			(size 0.4318 0.4318)
			(layers "F.Cu" "F.Mask" "F.Paste")
			(net "GND")
		)
		(pad "ED44" smd circle
			(at -2.427732 21.325332 270)
			(size 0.4318 0.4318)
			(layers "F.Cu" "F.Mask" "F.Paste")
			(net "M_E_CPU1_SA_CA<6>")
		)
		(pad "ED47" smd circle
			(at 1.613916 21.435314 270)
			(size 0.4318 0.4318)
			(layers "F.Cu" "F.Mask" "F.Paste")
			(net "M_H_CPU1_SB_RSP<1>")
		)
		(pad "ED49" smd circle
			(at 3.241802 21.435314 270)
			(size 0.4318 0.4318)
			(layers "F.Cu" "F.Mask" "F.Paste")
			(net "GND")
		)
		(pad "ED51" smd circle
			(at 4.869434 21.435314 270)
			(size 0.4318 0.4318)
			(layers "F.Cu" "F.Mask" "F.Paste")
			(net "M_F_CPU1_SA_CA<2>")
		)
		(pad "ED53" smd circle
			(at 6.49732 21.435314 270)
			(size 0.4318 0.4318)
			(layers "F.Cu" "F.Mask" "F.Paste")
			(net "M_F_CPU1_SA_CS_N<3>")
		)
		(pad "ED55" smd circle
			(at 8.124952 21.435314 270)
			(size 0.4318 0.4318)
			(layers "F.Cu" "F.Mask" "F.Paste")
			(net "GND")
		)
		(pad "ED57" smd circle
			(at 9.752838 21.435314 270)
			(size 0.4318 0.4318)
			(layers "F.Cu" "F.Mask" "F.Paste")
			(net "M_F_CPU1_SA_CB<4>")
		)
		(pad "ED59" smd circle
			(at 11.380724 21.435314 270)
			(size 0.4318 0.4318)
			(layers "F.Cu" "F.Mask" "F.Paste")
			(net "M_F_CPU1_SA_CB<1>")
		)
		(pad "ED61" smd circle
			(at 13.008356 21.435314 270)
			(size 0.4318 0.4318)
			(layers "F.Cu" "F.Mask" "F.Paste")
			(net "GND")
		)
		(pad "ED63" smd circle
			(at 14.635988 21.435314 270)
			(size 0.4318 0.4318)
			(layers "F.Cu" "F.Mask" "F.Paste")
			(net "M_F_CPU1_SA_DQ<20>")
		)
		(pad "ED65" smd circle
			(at 16.263874 21.435314 270)
			(size 0.4318 0.4318)
			(layers "F.Cu" "F.Mask" "F.Paste")
			(net "M_F_CPU1_SA_DQ<17>")
		)
		(pad "ED67" smd circle
			(at 17.89176 21.435314 270)
			(size 0.4318 0.4318)
			(layers "F.Cu" "F.Mask" "F.Paste")
			(net "GND")
		)
		(pad "ED69" smd circle
			(at 19.519392 21.435314 270)
			(size 0.4318 0.4318)
			(layers "F.Cu" "F.Mask" "F.Paste")
			(net "M_E_CPU1_SA_DQ<12>")
		)
		(pad "ED71" smd circle
			(at 21.147278 21.435314 270)
			(size 0.4318 0.4318)
			(layers "F.Cu" "F.Mask" "F.Paste")
			(net "M_E_CPU1_SA_DQ<9>")
		)
		(pad "ED73" smd circle
			(at 22.77491 21.435314 270)
			(size 0.4318 0.4318)
			(layers "F.Cu" "F.Mask" "F.Paste")
			(net "GND")
		)
		(pad "ED75" smd circle
			(at 24.402796 21.435314 270)
			(size 0.4318 0.4318)
			(layers "F.Cu" "F.Mask" "F.Paste")
			(net "M_F_CPU1_SA_DQ<4>")
		)
		(pad "ED77" smd circle
			(at 26.030682 21.435314 270)
			(size 0.4318 0.4318)
			(layers "F.Cu" "F.Mask" "F.Paste")
			(net "M_F_CPU1_SA_DQ<2>")
		)
		(pad "ED79" smd circle
			(at 27.658314 21.435314 270)
			(size 0.4318 0.4318)
			(layers "F.Cu" "F.Mask" "F.Paste")
			(net "PVCCFA_EHV_FIVRA_CPU1")
		)
		(pad "ED81" smd circle
			(at 29.2862 21.435314 270)
			(size 0.4318 0.4318)
			(layers "F.Cu" "F.Mask" "F.Paste")
			(net "GND")
		)
		(pad "ED83" smd circle
			(at 30.914086 21.435314 270)
			(size 0.4318 0.4318)
			(layers "F.Cu" "F.Mask" "F.Paste")
			(net "GND")
		)
		(pad "ED85" smd circle
			(at 32.541718 21.435314 270)
			(size 0.4318 0.4318)
			(layers "F.Cu" "F.Mask" "F.Paste")
			(net "PVCCFA_EHV_FIVRA_CPU1")
		)
		(pad "ED87" smd circle
			(at 34.169604 21.435314 270)
			(size 0.4318 0.4318)
			(layers "F.Cu" "F.Mask" "F.Paste")
			(net "P5E_CPU1_PE3_TX_DP<0>")
		)
		(pad "ED89" smd circle
			(at 35.797236 21.435314 270)
			(size 0.4318 0.4318)
			(layers "F.Cu" "F.Mask" "F.Paste")
			(net "PVCCFA_EHV_FIVRA_CPU1")
		)
		(pad "ED91" smd oval
			(at 37.425122 21.435314)
			(size 0.381 0.4826)
			(drill
				(offset 0 -0.0508)
			)
			(layers "F.Cu" "F.Mask" "F.Paste")
			(net "P5E_CPU1_PE3_RX_DN<1>")
		)
		(pad "EE3" smd circle
			(at -35.797236 21.795486 270)
			(size 0.4318 0.4318)
			(layers "F.Cu" "F.Mask" "F.Paste")
			(net "UPI_CPU0_CPU1_P0P1_DN<1>")
		)
		(pad "EE5" smd circle
			(at -34.169604 21.795486 270)
			(size 0.4318 0.4318)
			(layers "F.Cu" "F.Mask" "F.Paste")
			(net "UPI_CPU1_CPU0_P1P0_DP<0>")
		)
		(pad "EE7" smd circle
			(at -32.541718 21.795486 270)
			(size 0.4318 0.4318)
			(layers "F.Cu" "F.Mask" "F.Paste")
			(net "PVCCFA_EHV_FIVRA_CPU1")
		)
		(pad "EE9" smd circle
			(at -30.914086 21.795486 270)
			(size 0.4318 0.4318)
			(layers "F.Cu" "F.Mask" "F.Paste")
			(net "P5E_CPU1_PE2_RX_DN<14>")
		)
		(pad "EE11" smd circle
			(at -29.2862 21.795486 270)
			(size 0.4318 0.4318)
			(layers "F.Cu" "F.Mask" "F.Paste")
			(net "PVCCFA_EHV_FIVRA_CPU1")
		)
		(pad "EE13" smd circle
			(at -27.658314 21.795486 270)
			(size 0.4318 0.4318)
			(layers "F.Cu" "F.Mask" "F.Paste")
			(net "P5E_CPU1_PE2_TX_DN<14>")
		)
		(pad "EE15" smd circle
			(at -26.030682 21.795486 270)
			(size 0.4318 0.4318)
			(layers "F.Cu" "F.Mask" "F.Paste")
			(net "PVCCFA_EHV_FIVRA_CPU1")
		)
		(pad "EE17" smd circle
			(at -24.402796 21.795486 270)
			(size 0.4318 0.4318)
			(layers "F.Cu" "F.Mask" "F.Paste")
			(net "GND")
		)
		(pad "EE19" smd circle
			(at -22.77491 21.795486 270)
			(size 0.4318 0.4318)
			(layers "F.Cu" "F.Mask" "F.Paste")
			(net "M_F_CPU1_SB_DQ<13>")
		)
		(pad "EE21" smd circle
			(at -21.147278 21.795486 270)
			(size 0.4318 0.4318)
			(layers "F.Cu" "F.Mask" "F.Paste")
			(net "M_F_CPU1_SB_DQS_DN<1>")
		)
		(pad "EE23" smd circle
			(at -19.519392 21.795486 270)
			(size 0.4318 0.4318)
			(layers "F.Cu" "F.Mask" "F.Paste")
			(net "M_F_CPU1_SB_DQ<8>")
		)
		(pad "EE25" smd circle
			(at -17.89176 21.795486 270)
			(size 0.4318 0.4318)
			(layers "F.Cu" "F.Mask" "F.Paste")
			(net "M_E_CPU1_SB_DQ<5>")
		)
		(pad "EE27" smd circle
			(at -16.263874 21.795486 270)
			(size 0.4318 0.4318)
			(layers "F.Cu" "F.Mask" "F.Paste")
			(net "M_E_CPU1_SB_DQS_DN<0>")
		)
		(pad "EE29" smd circle
			(at -14.635988 21.795486 270)
			(size 0.4318 0.4318)
			(layers "F.Cu" "F.Mask" "F.Paste")
			(net "M_E_CPU1_SB_DQ<0>")
		)
		(pad "EE31" smd circle
			(at -13.008356 21.795486 270)
			(size 0.4318 0.4318)
			(layers "F.Cu" "F.Mask" "F.Paste")
			(net "M_F_CPU1_SB_CB<1>")
		)
		(pad "EE33" smd circle
			(at -11.380724 21.795486 270)
			(size 0.4318 0.4318)
			(layers "F.Cu" "F.Mask" "F.Paste")
			(net "M_F_CPU1_SB_DQS_DN<9>")
		)
		(pad "EE35" smd circle
			(at -9.752838 21.795486 270)
			(size 0.4318 0.4318)
			(layers "F.Cu" "F.Mask" "F.Paste")
			(net "M_F_CPU1_SB_CB<4>")
		)
		(pad "EE37" smd circle
			(at -8.124952 21.795486 270)
			(size 0.4318 0.4318)
			(layers "F.Cu" "F.Mask" "F.Paste")
			(net "M_F_CPU1_SB_CS_N<3>")
		)
		(pad "EE39" smd circle
			(at -6.49732 21.795486 270)
			(size 0.4318 0.4318)
			(layers "F.Cu" "F.Mask" "F.Paste")
			(net "GND")
		)
		(pad "EE41" smd circle
			(at -4.869434 21.795486 270)
			(size 0.4318 0.4318)
			(layers "F.Cu" "F.Mask" "F.Paste")
			(net "M_F_CPU1_SB_CA<2>")
		)
		(pad "EE43" smd circle
			(at -3.241802 21.795486 270)
			(size 0.4318 0.4318)
			(layers "F.Cu" "F.Mask" "F.Paste")
			(net "M_E_CPU1_SA_PAR")
		)
		(pad "EE45" smd circle
			(at -1.613916 21.795486 270)
			(size 0.4318 0.4318)
			(layers "F.Cu" "F.Mask" "F.Paste")
			(net "M_E_CPU1_CLK_DN<1>")
		)
		(pad "EE48" smd circle
			(at 2.427732 21.905468 270)
			(size 0.4318 0.4318)
			(layers "F.Cu" "F.Mask" "F.Paste")
			(net "M_H_CPU1_SB_RSP<0>")
		)
		(pad "EE50" smd circle
			(at 4.055618 21.905468 270)
			(size 0.4318 0.4318)
			(layers "F.Cu" "F.Mask" "F.Paste")
			(net "M_F_CPU1_SA_CA<4>")
		)
		(pad "EE52" smd circle
			(at 5.68325 21.905468 270)
			(size 0.4318 0.4318)
			(layers "F.Cu" "F.Mask" "F.Paste")
			(net "GND")
		)
		(pad "EE54" smd circle
			(at 7.311136 21.905468 270)
			(size 0.4318 0.4318)
			(layers "F.Cu" "F.Mask" "F.Paste")
			(net "M_F_CPU1_SA_CS_N<2>")
		)
		(pad "EE56" smd circle
			(at 8.939022 21.905468 270)
			(size 0.4318 0.4318)
			(layers "F.Cu" "F.Mask" "F.Paste")
			(net "M_F_CPU1_SA_CB<5>")
		)
		(pad "EE58" smd circle
			(at 10.566654 21.905468 270)
			(size 0.4318 0.4318)
			(layers "F.Cu" "F.Mask" "F.Paste")
			(net "M_F_CPU1_SA_DQS_DN<4>")
		)
		(pad "EE60" smd circle
			(at 12.19454 21.905468 270)
			(size 0.4318 0.4318)
			(layers "F.Cu" "F.Mask" "F.Paste")
			(net "M_F_CPU1_SA_CB<0>")
		)
		(pad "EE62" smd circle
			(at 13.822426 21.905468 270)
			(size 0.4318 0.4318)
			(layers "F.Cu" "F.Mask" "F.Paste")
			(net "M_F_CPU1_SA_DQ<21>")
		)
		(pad "EE64" smd circle
			(at 15.450058 21.905468 270)
			(size 0.4318 0.4318)
			(layers "F.Cu" "F.Mask" "F.Paste")
			(net "M_F_CPU1_SA_DQS_DP<2>")
		)
		(pad "EE66" smd circle
			(at 17.07769 21.905468 270)
			(size 0.4318 0.4318)
			(layers "F.Cu" "F.Mask" "F.Paste")
			(net "M_F_CPU1_SA_DQ<16>")
		)
		(pad "EE68" smd circle
			(at 18.705576 21.905468 270)
			(size 0.4318 0.4318)
			(layers "F.Cu" "F.Mask" "F.Paste")
			(net "M_E_CPU1_SA_DQ<13>")
		)
		(pad "EE70" smd circle
			(at 20.333462 21.905468 270)
			(size 0.4318 0.4318)
			(layers "F.Cu" "F.Mask" "F.Paste")
			(net "M_E_CPU1_SA_DQS_DP<1>")
		)
		(pad "EE72" smd circle
			(at 21.961094 21.905468 270)
			(size 0.4318 0.4318)
			(layers "F.Cu" "F.Mask" "F.Paste")
			(net "M_E_CPU1_SA_DQ<8>")
		)
		(pad "EE74" smd circle
			(at 23.58898 21.905468 270)
			(size 0.4318 0.4318)
			(layers "F.Cu" "F.Mask" "F.Paste")
			(net "M_F_CPU1_SA_DQ<5>")
		)
		(pad "EE76" smd circle
			(at 25.216612 21.905468 270)
			(size 0.4318 0.4318)
			(layers "F.Cu" "F.Mask" "F.Paste")
			(net "M_F_CPU1_SA_DQS_DN<0>")
		)
		(pad "EE78" smd circle
			(at 26.844498 21.905468 270)
			(size 0.4318 0.4318)
			(layers "F.Cu" "F.Mask" "F.Paste")
			(net "GND")
		)
		(pad "EE80" smd circle
			(at 28.472384 21.905468 270)
			(size 0.4318 0.4318)
			(layers "F.Cu" "F.Mask" "F.Paste")
			(net "GND")
		)
		(pad "EE82" smd circle
			(at 30.100016 21.905468 270)
			(size 0.4318 0.4318)
			(layers "F.Cu" "F.Mask" "F.Paste")
			(net "GND")
		)
		(pad "EE84" smd circle
			(at 31.727902 21.905468 270)
			(size 0.4318 0.4318)
			(layers "F.Cu" "F.Mask" "F.Paste")
			(net "PVCCFA_EHV_FIVRA_CPU1")
		)
		(pad "EE86" smd circle
			(at 33.355534 21.905468 270)
			(size 0.4318 0.4318)
			(layers "F.Cu" "F.Mask" "F.Paste")
			(net "P5E_CPU1_PE3_TX_DN<0>")
		)
		(pad "EE88" smd circle
			(at 34.98342 21.905468 270)
			(size 0.4318 0.4318)
			(layers "F.Cu" "F.Mask" "F.Paste")
			(net "GND")
		)
		(pad "EE90" smd oval
			(at 36.611306 21.905468)
			(size 0.381 0.4826)
			(drill
				(offset 0 -0.0508)
			)
			(layers "F.Cu" "F.Mask" "F.Paste")
			(net "P5E_CPU1_PE3_RX_DP<1>")
		)
		(pad "EF2" smd oval
			(at -36.611306 22.265386 180)
			(size 0.381 0.4826)
			(drill
				(offset 0 -0.0508)
			)
			(layers "F.Cu" "F.Mask" "F.Paste")
			(net "GND")
		)
		(pad "EF4" smd circle
			(at -34.98342 22.265386 270)
			(size 0.4318 0.4318)
			(layers "F.Cu" "F.Mask" "F.Paste")
			(net "GND")
		)
		(pad "EF6" smd circle
			(at -33.355534 22.265386 270)
			(size 0.4318 0.4318)
			(layers "F.Cu" "F.Mask" "F.Paste")
			(net "UPI_CPU1_CPU0_P1P0_DN<0>")
		)
		(pad "EF8" smd circle
			(at -31.727902 22.265386 270)
			(size 0.4318 0.4318)
			(layers "F.Cu" "F.Mask" "F.Paste")
			(net "GND")
		)
		(pad "EF10" smd circle
			(at -30.100016 22.265386 270)
			(size 0.4318 0.4318)
			(layers "F.Cu" "F.Mask" "F.Paste")
			(net "P5E_CPU1_PE2_RX_DP<14>")
		)
		(pad "EF12" smd circle
			(at -28.472384 22.265386 270)
			(size 0.4318 0.4318)
			(layers "F.Cu" "F.Mask" "F.Paste")
			(net "GND")
		)
		(pad "EF14" smd circle
			(at -26.844498 22.265386 270)
			(size 0.4318 0.4318)
			(layers "F.Cu" "F.Mask" "F.Paste")
			(net "P5E_CPU1_PE2_TX_DN<15>")
		)
		(pad "EF16" smd circle
			(at -25.216612 22.265386 270)
			(size 0.4318 0.4318)
			(layers "F.Cu" "F.Mask" "F.Paste")
			(net "GND")
		)
		(pad "EF18" smd circle
			(at -23.58898 22.265386 270)
			(size 0.4318 0.4318)
			(layers "F.Cu" "F.Mask" "F.Paste")
			(net "GND")
		)
		(pad "EF20" smd circle
			(at -21.961094 22.265386 270)
			(size 0.4318 0.4318)
			(layers "F.Cu" "F.Mask" "F.Paste")
			(net "GND")
		)
		(pad "EF22" smd circle
			(at -20.333462 22.265386 270)
			(size 0.4318 0.4318)
			(layers "F.Cu" "F.Mask" "F.Paste")
			(net "GND")
		)
	)
)
